(kicad_pcb
	(version 20241229)
	(generator "pcbnew")
	(generator_version "9.0")
	(general
		(thickness 1.552)
		(legacy_teardrops no)
	)
	(paper "A4")
	(title_block
		(date "2023-07-25")
		(rev "1.1.4")
		(comment 9 "footprints 368-372 of 379")
	)
	(layers
		(0 "F.Cu" signal)
		(4 "In1.Cu" signal)
		(6 "In2.Cu" signal)
		(8 "In3.Cu" signal)
		(10 "In4.Cu" signal)
		(12 "In5.Cu" signal)
		(14 "In6.Cu" signal)
		(2 "B.Cu" signal)
		(9 "F.Adhes" user "F.Adhesive")
		(11 "B.Adhes" user "B.Adhesive")
		(13 "F.Paste" user)
		(15 "B.Paste" user)
		(5 "F.SilkS" user "F.Silkscreen")
		(7 "B.SilkS" user "B.Silkscreen")
		(1 "F.Mask" user)
		(3 "B.Mask" user)
		(17 "Dwgs.User" user "User.Drawings")
		(19 "Cmts.User" user "User.Comments")
		(21 "Eco1.User" user "User.Eco1")
		(23 "Eco2.User" user "User.Eco2")
		(25 "Edge.Cuts" user)
		(27 "Margin" user)
		(31 "F.CrtYd" user "F.Courtyard")
		(29 "B.CrtYd" user "B.Courtyard")
		(35 "F.Fab" user)
		(33 "B.Fab" user)
	)
	(footprint "antmicro-footprints:SOT-23-6"
		(layer "B.Cu")
		(at 158.54 72.35 -90)
		(property "Reference" "U4"
			(at -1.71 -2.09 180)
			(layer "B.SilkS")
			(effects
				(font
					(size 0.65 0.65)
					(thickness 0.15)
				)
				(justify left bottom mirror)
			)
		)
		(property "Value" "DIO7553ST6"
			(at -1.75 -2.75 90)
			(layer "B.Fab")
			(hide yes)
			(effects
				(font
					(size 0.7 0.7)
					(thickness 0.15)
				)
				(justify left bottom mirror)
			)
		)
		(property "Datasheet" "https://www.mouser.com/datasheet/2/802/7e5c577022fb784effcb3cdb25b437c0-1815562.pdf"
			(at 0 0 270)
			(layer "F.Fab")
			(hide yes)
			(effects
				(font
					(size 1.27 1.27)
					(thickness 0.15)
				)
			)
		)
		(property "Description" "Power switch"
			(at 0 0 270)
			(layer "F.Fab")
			(hide yes)
			(effects
				(font
					(size 1.27 1.27)
					(thickness 0.15)
				)
			)
		)
		(property "Author" "Antmicro"
			(at 86.19 230.89 0)
			(layer "B.Fab")
			(hide yes)
			(effects
				(font
					(size 1 1)
					(thickness 0.15)
				)
				(justify mirror)
			)
		)
		(property "License" "Apache-2.0"
			(at 86.19 230.89 0)
			(layer "B.Fab")
			(hide yes)
			(effects
				(font
					(size 1 1)
					(thickness 0.15)
				)
				(justify mirror)
			)
		)
		(property "MPN" "DIO7553ST6"
			(at 86.19 230.89 0)
			(layer "B.Fab")
			(hide yes)
			(effects
				(font
					(size 1 1)
					(thickness 0.15)
				)
				(justify mirror)
			)
		)
		(property "Manufacturer" "DIOO Microcircuits"
			(at 86.19 230.89 0)
			(layer "B.Fab")
			(hide yes)
			(effects
				(font
					(size 1 1)
					(thickness 0.15)
				)
				(justify mirror)
			)
		)
		(sheetname "/Power Supply/")
		(sheetfile "supply.kicad_sch")
		(attr smd)
		(fp_line
			(start -1.45 0.757)
			(end -1.45 0.457)
			(stroke
				(width 0.12)
				(type solid)
			)
			(layer "B.SilkS")
		)
		(fp_line
			(start -1.3 0.757)
			(end -1.45 0.757)
			(stroke
				(width 0.12)
				(type solid)
			)
			(layer "B.SilkS")
		)
		(fp_line
			(start 1.3 0.757)
			(end 1.45 0.757)
			(stroke
				(width 0.12)
				(type solid)
			)
			(layer "B.SilkS")
		)
		(fp_line
			(start 1.45 0.757)
			(end 1.45 0.457)
			(stroke
				(width 0.12)
				(type solid)
			)
			(layer "B.SilkS")
		)
		(fp_line
			(start -1.45 -0.643)
			(end -1.45 -0.343)
			(stroke
				(width 0.12)
				(type solid)
			)
			(layer "B.SilkS")
		)
		(fp_line
			(start 1.3 -0.643)
			(end 1.45 -0.643)
			(stroke
				(width 0.12)
				(type solid)
			)
			(layer "B.SilkS")
		)
		(fp_line
			(start 1.45 -0.643)
			(end 1.45 -0.343)
			(stroke
				(width 0.12)
				(type solid)
			)
			(layer "B.SilkS")
		)
		(fp_rect
			(start -1.55 1.85)
			(end 1.55 -1.75)
			(stroke
				(width 0.05)
				(type solid)
			)
			(fill no)
			(layer "B.CrtYd")
		)
		(fp_line
			(start -1.5 0.757)
			(end 1.5 0.757)
			(stroke
				(width 0.1)
				(type solid)
			)
			(layer "B.Fab")
		)
		(fp_line
			(start 1.5 0.757)
			(end 1.5 -0.643)
			(stroke
				(width 0.1)
				(type solid)
			)
			(layer "B.Fab")
		)
		(fp_line
			(start -1.5 -0.643)
			(end -1.5 0.757)
			(stroke
				(width 0.1)
				(type solid)
			)
			(layer "B.Fab")
		)
		(fp_line
			(start 1.5 -0.643)
			(end -1.5 -0.643)
			(stroke
				(width 0.1)
				(type solid)
			)
			(layer "B.Fab")
		)
		(fp_text user "."
			(at -1.4 -1.2 90)
			(layer "B.SilkS")
			(effects
				(font
					(size 1 1)
					(thickness 0.15)
				)
				(justify mirror)
			)
		)
		(fp_text user "Author: Antmicro"
			(at -1.829 -5.25 90)
			(layer "B.Fab")
			(effects
				(font
					(size 0.7 0.7)
					(thickness 0.15)
				)
				(justify left bottom mirror)
			)
		)
		(fp_text user "${REFERENCE}"
			(at -1.75 -4 90)
			(layer "B.Fab")
			(effects
				(font
					(size 0.7 0.7)
					(thickness 0.15)
				)
				(justify left bottom mirror)
			)
		)
		(fp_text user "License: Apache-2.0"
			(at -1.75 -6.5 90)
			(layer "B.Fab")
			(effects
				(font
					(size 0.7 0.7)
					(thickness 0.15)
				)
				(justify left bottom mirror)
			)
		)
		(pad "1" smd roundrect
			(at -0.954 -1.1 270)
			(size 0.55 1)
			(layers "B.Cu" "B.Mask" "B.Paste")
			(roundrect_rratio 0.15)
			(net 329 "/Power Supply/FFC2_5V_1")
			(pinfunction "IN")
			(pintype "power_in")
		)
		(pad "2" smd roundrect
			(at -0.003 -1.1 270)
			(size 0.55 1)
			(layers "B.Cu" "B.Mask" "B.Paste")
			(roundrect_rratio 0.15)
			(net 1 "GND")
			(pinfunction "GND")
			(pintype "power_in")
		)
		(pad "3" smd roundrect
			(at 0.947 -1.1 270)
			(size 0.55 1)
			(layers "B.Cu" "B.Mask" "B.Paste")
			(roundrect_rratio 0.15)
			(net 259 "Net-(Q1-D)")
			(pinfunction "EN")
			(pintype "input")
		)
		(pad "4" smd roundrect
			(at 0.947 1.214 270)
			(size 0.55 1)
			(layers "B.Cu" "B.Mask" "B.Paste")
			(roundrect_rratio 0.15)
			(net 305 "/Power Supply/~{FAULT}")
			(pinfunction "~{FAULT}")
			(pintype "output")
		)
		(pad "5" smd roundrect
			(at -0.003 1.214 270)
			(size 0.55 1)
			(layers "B.Cu" "B.Mask" "B.Paste")
			(roundrect_rratio 0.15)
			(net 349 "Net-(U4-ILIM)")
			(pinfunction "ILIM")
			(pintype "passive")
		)
		(pad "6" smd roundrect
			(at -0.954 1.214 270)
			(size 0.55 1)
			(layers "B.Cu" "B.Mask" "B.Paste")
			(roundrect_rratio 0.15)
			(net 304 "/Power Supply/5V_I")
			(pinfunction "OUT")
			(pintype "power_out")
		)
	)
	(footprint "antmicro-footprints:C_0402_1005Metric"
		(layer "B.Cu")
		(at 153.03 98.35 90)
		(descr "Capacitor SMD 0402")
		(tags "capacitor SMD 0402")
		(property "Reference" "C1"
			(at 0.91 0.4 90)
			(layer "B.SilkS")
			(effects
				(font
					(size 0.65 0.65)
					(thickness 0.15)
				)
				(justify right bottom mirror)
			)
		)
		(property "Value" "C_100n_0402"
			(at 0 -1.4 90)
			(layer "B.Fab")
			(hide yes)
			(effects
				(font
					(size 0.7 0.7)
					(thickness 0.15)
				)
				(justify right bottom mirror)
			)
		)
		(property "Datasheet" "https://www.murata.com/products/productdetail?partno=GRM155R61H104KE14%23"
			(at 0 0 90)
			(layer "F.Fab")
			(hide yes)
			(effects
				(font
					(size 1.27 1.27)
					(thickness 0.15)
				)
			)
		)
		(property "Description" "SMD Multilayer Ceramic Capacitor, 0.1 µF, 50 V, 0402 [1005 Metric], ± 10%, X5R, GRM Series"
			(at 0 0 90)
			(layer "F.Fab")
			(hide yes)
			(effects
				(font
					(size 1.27 1.27)
					(thickness 0.15)
				)
			)
		)
		(property "Author" "Antmicro"
			(at 251.38 -54.68 0)
			(layer "B.Fab")
			(hide yes)
			(effects
				(font
					(size 1 1)
					(thickness 0.15)
				)
				(justify mirror)
			)
		)
		(property "Dielectric" "X5R"
			(at 251.38 -54.68 0)
			(layer "B.Fab")
			(hide yes)
			(effects
				(font
					(size 1 1)
					(thickness 0.15)
				)
				(justify mirror)
			)
		)
		(property "License" "Apache-2.0"
			(at 251.38 -54.68 0)
			(layer "B.Fab")
			(hide yes)
			(effects
				(font
					(size 1 1)
					(thickness 0.15)
				)
				(justify mirror)
			)
		)
		(property "MPN" "GRM155R61H104KE14D"
			(at 251.38 -54.68 0)
			(layer "B.Fab")
			(hide yes)
			(effects
				(font
					(size 1 1)
					(thickness 0.15)
				)
				(justify mirror)
			)
		)
		(property "Manufacturer" "Murata"
			(at 251.38 -54.68 0)
			(layer "B.Fab")
			(hide yes)
			(effects
				(font
					(size 1 1)
					(thickness 0.15)
				)
				(justify mirror)
			)
		)
		(property "Val" "100n"
			(at 251.38 -54.68 0)
			(layer "B.Fab")
			(hide yes)
			(effects
				(font
					(size 1 1)
					(thickness 0.15)
				)
				(justify mirror)
			)
		)
		(property "Voltage" "50V"
			(at 251.38 -54.68 0)
			(layer "B.Fab")
			(hide yes)
			(effects
				(font
					(size 1 1)
					(thickness 0.15)
				)
				(justify mirror)
			)
		)
		(sheetname "/Power Supply/")
		(sheetfile "supply.kicad_sch")
		(attr smd)
		(fp_rect
			(start -0.925 0.47)
			(end 0.925 -0.47)
			(stroke
				(width 0.05)
				(type default)
			)
			(fill no)
			(layer "B.CrtYd")
		)
		(fp_line
			(start 0.504 -0.248)
			(end -0.494 -0.248)
			(stroke
				(width 0.15)
				(type solid)
			)
			(layer "B.Fab")
		)
		(fp_line
			(start -0.494 -0.248)
			(end -0.494 0.25)
			(stroke
				(width 0.15)
				(type solid)
			)
			(layer "B.Fab")
		)
		(fp_line
			(start 0.504 0.25)
			(end 0.504 -0.248)
			(stroke
				(width 0.15)
				(type solid)
			)
			(layer "B.Fab")
		)
		(fp_line
			(start -0.494 0.25)
			(end 0.504 0.25)
			(stroke
				(width 0.15)
				(type solid)
			)
			(layer "B.Fab")
		)
		(fp_text user "Author: Antmicro"
			(at -0.939 -3.399 270)
			(layer "B.Fab")
			(effects
				(font
					(size 0.7 0.7)
					(thickness 0.15)
				)
				(justify left bottom mirror)
			)
		)
		(fp_text user "${REFERENCE}"
			(at -0.939 -4.599 270)
			(layer "B.Fab")
			(effects
				(font
					(size 0.7 0.7)
					(thickness 0.15)
				)
				(justify left bottom mirror)
			)
		)
		(fp_text user "License: Apache-2.0"
			(at -0.939 -5.799 270)
			(layer "B.Fab")
			(effects
				(font
					(size 0.7 0.7)
					(thickness 0.15)
				)
				(justify left bottom mirror)
			)
		)
		(pad "1" smd roundrect
			(at -0.48 0 90)
			(size 0.59 0.64)
			(layers "B.Cu" "B.Mask" "B.Paste")
			(roundrect_rratio 0.25)
			(net 1 "GND")
			(pintype "passive")
		)
		(pad "2" smd roundrect
			(at 0.48 0 90)
			(size 0.59 0.64)
			(layers "B.Cu" "B.Mask" "B.Paste")
			(roundrect_rratio 0.25)
			(net 14 "+5V")
			(pintype "passive")
		)
	)
	(footprint "antmicro-footprints:C_0402_1005Metric"
		(layer "B.Cu")
		(at 120.51 70.12 90)
		(descr "Capacitor SMD 0402")
		(tags "capacitor SMD 0402")
		(property "Reference" "C48"
			(at -0.92 1.42 90)
			(layer "B.SilkS")
			(effects
				(font
					(size 0.65 0.65)
					(thickness 0.15)
				)
				(justify right bottom mirror)
			)
		)
		(property "Value" "C_100n_0402"
			(at 0 -1.4 90)
			(layer "B.Fab")
			(hide yes)
			(effects
				(font
					(size 0.7 0.7)
					(thickness 0.15)
				)
				(justify right bottom mirror)
			)
		)
		(property "Datasheet" "https://www.murata.com/products/productdetail?partno=GRM155R61H104KE14%23"
			(at 0 0 90)
			(layer "F.Fab")
			(hide yes)
			(effects
				(font
					(size 1.27 1.27)
					(thickness 0.15)
				)
			)
		)
		(property "Description" "SMD Multilayer Ceramic Capacitor, 0.1 µF, 50 V, 0402 [1005 Metric], ± 10%, X5R, GRM Series"
			(at 0 0 90)
			(layer "F.Fab")
			(hide yes)
			(effects
				(font
					(size 1.27 1.27)
					(thickness 0.15)
				)
			)
		)
		(property "Author" "Antmicro"
			(at 190.63 -50.39 0)
			(layer "B.Fab")
			(hide yes)
			(effects
				(font
					(size 1 1)
					(thickness 0.15)
				)
				(justify mirror)
			)
		)
		(property "Dielectric" "X5R"
			(at 190.63 -50.39 0)
			(layer "B.Fab")
			(hide yes)
			(effects
				(font
					(size 1 1)
					(thickness 0.15)
				)
				(justify mirror)
			)
		)
		(property "License" "Apache-2.0"
			(at 190.63 -50.39 0)
			(layer "B.Fab")
			(hide yes)
			(effects
				(font
					(size 1 1)
					(thickness 0.15)
				)
				(justify mirror)
			)
		)
		(property "MPN" "GRM155R61H104KE14D"
			(at 190.63 -50.39 0)
			(layer "B.Fab")
			(hide yes)
			(effects
				(font
					(size 1 1)
					(thickness 0.15)
				)
				(justify mirror)
			)
		)
		(property "Manufacturer" "Murata"
			(at 190.63 -50.39 0)
			(layer "B.Fab")
			(hide yes)
			(effects
				(font
					(size 1 1)
					(thickness 0.15)
				)
				(justify mirror)
			)
		)
		(property "Val" "100n"
			(at 190.63 -50.39 0)
			(layer "B.Fab")
			(hide yes)
			(effects
				(font
					(size 1 1)
					(thickness 0.15)
				)
				(justify mirror)
			)
		)
		(property "Voltage" "50V"
			(at 190.63 -50.39 0)
			(layer "B.Fab")
			(hide yes)
			(effects
				(font
					(size 1 1)
					(thickness 0.15)
				)
				(justify mirror)
			)
		)
		(sheetname "/DDR3/")
		(sheetfile "ddr3.kicad_sch")
		(attr smd)
		(fp_rect
			(start -0.925 0.47)
			(end 0.925 -0.47)
			(stroke
				(width 0.05)
				(type default)
			)
			(fill no)
			(layer "B.CrtYd")
		)
		(fp_line
			(start 0.504 -0.248)
			(end -0.494 -0.248)
			(stroke
				(width 0.15)
				(type solid)
			)
			(layer "B.Fab")
		)
		(fp_line
			(start -0.494 -0.248)
			(end -0.494 0.25)
			(stroke
				(width 0.15)
				(type solid)
			)
			(layer "B.Fab")
		)
		(fp_line
			(start 0.504 0.25)
			(end 0.504 -0.248)
			(stroke
				(width 0.15)
				(type solid)
			)
			(layer "B.Fab")
		)
		(fp_line
			(start -0.494 0.25)
			(end 0.504 0.25)
			(stroke
				(width 0.15)
				(type solid)
			)
			(layer "B.Fab")
		)
		(fp_text user "${REFERENCE}"
			(at -0.939 -4.599 270)
			(layer "B.Fab")
			(effects
				(font
					(size 0.7 0.7)
					(thickness 0.15)
				)
				(justify left bottom mirror)
			)
		)
		(fp_text user "Author: Antmicro"
			(at -0.939 -3.399 270)
			(layer "B.Fab")
			(effects
				(font
					(size 0.7 0.7)
					(thickness 0.15)
				)
				(justify left bottom mirror)
			)
		)
		(fp_text user "License: Apache-2.0"
			(at -0.939 -5.799 270)
			(layer "B.Fab")
			(effects
				(font
					(size 0.7 0.7)
					(thickness 0.15)
				)
				(justify left bottom mirror)
			)
		)
		(pad "1" smd roundrect
			(at -0.48 0 90)
			(size 0.59 0.64)
			(layers "B.Cu" "B.Mask" "B.Paste")
			(roundrect_rratio 0.25)
			(net 1 "GND")
			(pintype "passive")
		)
		(pad "2" smd roundrect
			(at 0.48 0 90)
			(size 0.59 0.64)
			(layers "B.Cu" "B.Mask" "B.Paste")
			(roundrect_rratio 0.25)
			(net 248 "+1V5")
			(pintype "passive")
		)
	)
	(footprint "antmicro-footprints:TP_SMD_0.75mm"
		(layer "B.Cu")
		(at 99.19 88.95 90)
		(property "Reference" "TP33"
			(at -0.59 0.34 90)
			(layer "B.SilkS")
			(effects
				(font
					(size 0.65 0.65)
					(thickness 0.15)
				)
				(justify left bottom mirror)
			)
		)
		(property "Value" "TP_0.75mm_SMD"
			(at 0 -1.2 90)
			(layer "B.Fab")
			(hide yes)
			(effects
				(font
					(size 0.7 0.7)
					(thickness 0.15)
				)
				(justify right bottom mirror)
			)
		)
		(property "Description" "SMT test point"
			(at 0 0 90)
			(layer "F.Fab")
			(hide yes)
			(effects
				(font
					(size 1.27 1.27)
					(thickness 0.15)
				)
			)
		)
		(property "Author" "Antmicro"
			(at 188.14 -10.24 0)
			(layer "B.Fab")
			(hide yes)
			(effects
				(font
					(size 1 1)
					(thickness 0.15)
				)
				(justify mirror)
			)
		)
		(property "License" "Apache-2.0"
			(at 188.14 -10.24 0)
			(layer "B.Fab")
			(hide yes)
			(effects
				(font
					(size 1 1)
					(thickness 0.15)
				)
				(justify mirror)
			)
		)
		(property "MPN" ""
			(at 188.14 -10.24 0)
			(layer "B.Fab")
			(hide yes)
			(effects
				(font
					(size 1 1)
					(thickness 0.15)
				)
				(justify mirror)
			)
		)
		(property "Manufacturer" ""
			(at 188.14 -10.24 0)
			(layer "B.Fab")
			(hide yes)
			(effects
				(font
					(size 1 1)
					(thickness 0.15)
				)
				(justify mirror)
			)
		)
		(sheetname "/SDI/")
		(sheetfile "sdi.kicad_sch")
		(attr exclude_from_pos_files)
		(fp_circle
			(center 0 0)
			(end 0.475 0)
			(stroke
				(width 0.05)
				(type default)
			)
			(fill no)
			(layer "B.CrtYd")
		)
		(fp_text user "Author: Antmicro"
			(at -0.4 -3.901 270)
			(layer "B.Fab")
			(effects
				(font
					(size 0.7 0.7)
					(thickness 0.15)
				)
				(justify left bottom mirror)
			)
		)
		(fp_text user "License: Apache-2.0"
			(at -0.4 -5.101 270)
			(layer "B.Fab")
			(effects
				(font
					(size 0.7 0.7)
					(thickness 0.15)
				)
				(justify left bottom mirror)
			)
		)
		(fp_text user "${REFERENCE}"
			(at -0.4 -2.7 270)
			(layer "B.Fab")
			(effects
				(font
					(size 0.7 0.7)
					(thickness 0.15)
				)
				(justify left bottom mirror)
			)
		)
		(pad "1" smd circle
			(at 0 0 90)
			(size 0.75 0.75)
			(layers "B.Cu" "B.Mask")
			(net 199 "/SDI/IOPROC_EN{slash}~{DIS}")
			(pinfunction "1")
			(pintype "passive")
		)
	)
	(footprint "antmicro-footprints:C_0603_1608Metric"
		(layer "B.Cu")
		(at 130.2 62.15 90)
		(descr "Capacitor SMD 0603")
		(tags "capacitor 0603")
		(property "Reference" "C7"
			(at -2.69 0.4 90)
			(layer "B.SilkS")
			(effects
				(font
					(size 0.65 0.65)
					(thickness 0.15)
				)
				(justify right bottom mirror)
			)
		)
		(property "Value" "C_22u_0603"
			(at 0 -1.6 90)
			(layer "B.Fab")
			(hide yes)
			(effects
				(font
					(size 0.7 0.7)
					(thickness 0.15)
				)
				(justify right bottom mirror)
			)
		)
		(property "Datasheet" "https://www.murata.com/products/productdetail?partno=GRM188R60J226MEA0%23"
			(at 0 0 90)
			(layer "F.Fab")
			(hide yes)
			(effects
				(font
					(size 1.27 1.27)
					(thickness 0.15)
				)
			)
		)
		(property "Description" "SMD Multilayer Ceramic Capacitor, 22 µF, 6.3 V, 0603 [1608 Metric], ± 20%, X5R, GRM Series"
			(at 0 0 90)
			(layer "F.Fab")
			(hide yes)
			(effects
				(font
					(size 1.27 1.27)
					(thickness 0.15)
				)
			)
		)
		(property "Author" "Antmicro"
			(at 192.38 -68.08 0)
			(layer "B.Fab")
			(hide yes)
			(effects
				(font
					(size 1 1)
					(thickness 0.15)
				)
				(justify mirror)
			)
		)
		(property "Dielectric" ""
			(at 192.38 -68.08 0)
			(layer "B.Fab")
			(hide yes)
			(effects
				(font
					(size 1 1)
					(thickness 0.15)
				)
				(justify mirror)
			)
		)
		(property "License" "Apache-2.0"
			(at 192.38 -68.08 0)
			(layer "B.Fab")
			(hide yes)
			(effects
				(font
					(size 1 1)
					(thickness 0.15)
				)
				(justify mirror)
			)
		)
		(property "MPN" "GRM188R60J226MEA0D"
			(at 192.38 -68.08 0)
			(layer "B.Fab")
			(hide yes)
			(effects
				(font
					(size 1 1)
					(thickness 0.15)
				)
				(justify mirror)
			)
		)
		(property "Manufacturer" "Murata"
			(at 192.38 -68.08 0)
			(layer "B.Fab")
			(hide yes)
			(effects
				(font
					(size 1 1)
					(thickness 0.15)
				)
				(justify mirror)
			)
		)
		(property "Val" "22u"
			(at 192.38 -68.08 0)
			(layer "B.Fab")
			(hide yes)
			(effects
				(font
					(size 1 1)
					(thickness 0.15)
				)
				(justify mirror)
			)
		)
		(property "Voltage" ""
			(at 192.38 -68.08 0)
			(layer "B.Fab")
			(hide yes)
			(effects
				(font
					(size 1 1)
					(thickness 0.15)
				)
				(justify mirror)
			)
		)
		(sheetname "/Power Supply/")
		(sheetfile "supply.kicad_sch")
		(attr smd)
		(fp_line
			(start -0.15 -0.4)
			(end 0.15 -0.4)
			(stroke
				(width 0.15)
				(type solid)
			)
			(layer "B.SilkS")
		)
		(fp_line
			(start -0.15 0.4)
			(end 0.15 0.4)
			(stroke
				(width 0.15)
				(type solid)
			)
			(layer "B.SilkS")
		)
		(fp_rect
			(start -1.25 0.65)
			(end 1.25 -0.65)
			(stroke
				(width 0.05)
				(type solid)
			)
			(fill no)
			(layer "B.CrtYd")
		)
		(fp_rect
			(start -0.8 0.4)
			(end 0.8 -0.4)
			(stroke
				(width 0.15)
				(type solid)
			)
			(fill no)
			(layer "B.Fab")
		)
		(fp_text user "${REFERENCE}"
			(at -1.682 -3.895 270)
			(layer "B.Fab")
			(effects
				(font
					(size 0.7 0.7)
					(thickness 0.15)
				)
				(justify left bottom mirror)
			)
		)
		(fp_text user "License: Apache-2.0"
			(at -1.682 -5.895 270)
			(layer "B.Fab")
			(effects
				(font
					(size 0.7 0.7)
					(thickness 0.15)
				)
				(justify left bottom mirror)
			)
		)
		(fp_text user "Author: Antmicro"
			(at -1.682 -4.894 270)
			(layer "B.Fab")
			(effects
				(font
					(size 0.7 0.7)
					(thickness 0.15)
				)
				(justify left bottom mirror)
			)
		)
		(pad "1" smd roundrect
			(at -0.7 0 90)
			(size 0.8 1)
			(layers "B.Cu" "B.Mask" "B.Paste")
			(roundrect_rratio 0.2)
			(net 1 "GND")
			(pintype "passive")
		)
		(pad "2" smd roundrect
			(at 0.7 0 90)
			(size 0.8 1)
			(layers "B.Cu" "B.Mask" "B.Paste")
			(roundrect_rratio 0.2)
			(net 6 "Vtt")
			(pintype "passive")
		)
	)
)
